(kicad_pcb
	(version 20260206)
	(generator "pcbnew")
	(generator_version "10.0")
	(general
		(thickness 1.5755)
		(legacy_teardrops no)
	)
	(paper "A4")
	(title_block
		(title "gnss-rcb-f9t — GPS_MODULE_ZED-F9T.PcbDoc")
		(comment 1 "Time Appliance Project (Time Card) / footprints 21-27 of 44")
	)
	(layers
		(0 "F.Cu" signal "Top Layer")
		(4 "In1.Cu" signal "Int1 (GND)")
		(6 "In2.Cu" signal "Int2 (GND)")
		(2 "B.Cu" signal "Bottom Layer")
		(9 "F.Adhes" user "F.Adhesive")
		(11 "B.Adhes" user "B.Adhesive")
		(13 "F.Paste" user "Top Paste")
		(15 "B.Paste" user "Bottom Paste")
		(5 "F.SilkS" user "Top Overlay")
		(7 "B.SilkS" user "Bottom Overlay")
		(1 "F.Mask" user "Top Solder")
		(3 "B.Mask" user "Bottom Solder")
		(17 "Dwgs.User" user "User.Drawings")
		(19 "Cmts.User" user "User.Comments")
		(21 "Eco1.User" user "User.Eco1")
		(23 "Eco2.User" user "User.Eco2")
		(25 "Edge.Cuts" user)
		(27 "Margin" user)
		(31 "F.CrtYd" user "Top Courtyard")
		(29 "B.CrtYd" user "Bottom Courtyard")
		(35 "F.Fab" user "Top Component Outline")
		(33 "B.Fab" user "Bottom Component Outline")
	)
	(footprint "Vault:DCU0008A_N"
		(layer "F.Cu")
		(at 165.8675 108.2523 -90)
		(property "Reference" "U2"
			(at -3.28225 0.3603 0)
			(unlocked yes)
			(layer "F.SilkS")
			(effects
				(font
					(size 0.8 0.8)
					(thickness 0.15)
				)
			)
		)
		(property "Value" "SN74LVC3G07DCUR"
			(at 2.530602 -9.813485 0)
			(unlocked yes)
			(layer "F.SilkS")
			(hide yes)
			(effects
				(font
					(size 1.524 1.524)
					(thickness 0.254)
				)
			)
		)
		(sheetname "ZED-F9T")
		(sheetfile "ZED-F9T.kicad_sch")
		(duplicate_pad_numbers_are_jumpers no)
		(fp_line
			(start -0.8 1.05)
			(end -0.8 -1.05)
			(stroke
				(width 0.2)
				(type solid)
			)
			(layer "F.SilkS")
		)
		(fp_line
			(start 0.8 1.05)
			(end -0.8 1.05)
			(stroke
				(width 0.2)
				(type solid)
			)
			(layer "F.SilkS")
		)
		(fp_line
			(start 0.8 1.05)
			(end 0.8 -1.05)
			(stroke
				(width 0.2)
				(type solid)
			)
			(layer "F.SilkS")
		)
		(fp_line
			(start 0.8 -1.05)
			(end -0.8 -1.05)
			(stroke
				(width 0.2)
				(type solid)
			)
			(layer "F.SilkS")
		)
		(fp_circle
			(center -1.6 -1.45)
			(end -1.725 -1.45)
			(stroke
				(width 0.25)
				(type solid)
			)
			(fill no)
			(layer "F.SilkS")
		)
		(fp_line
			(start -2.225 1.3)
			(end -2.225 -1.3)
			(stroke
				(width 0.05)
				(type solid)
			)
			(layer "F.CrtYd")
		)
		(fp_line
			(start 2.225 1.3)
			(end -2.225 1.3)
			(stroke
				(width 0.05)
				(type solid)
			)
			(layer "F.CrtYd")
		)
		(fp_line
			(start 2.225 1.3)
			(end 2.225 -1.3)
			(stroke
				(width 0.05)
				(type solid)
			)
			(layer "F.CrtYd")
		)
		(fp_line
			(start 0 0.5)
			(end 0 -0.5)
			(stroke
				(width 0.1)
				(type solid)
			)
			(layer "F.CrtYd")
		)
		(fp_line
			(start 0.5 0)
			(end -0.5 0)
			(stroke
				(width 0.1)
				(type solid)
			)
			(layer "F.CrtYd")
		)
		(fp_line
			(start 2.225 -1.3)
			(end -2.225 -1.3)
			(stroke
				(width 0.05)
				(type solid)
			)
			(layer "F.CrtYd")
		)
		(pad "1" smd roundrect
			(at -1.6 -0.75)
			(size 0.3 0.8)
			(layers "F.Cu" "F.Mask" "F.Paste")
			(roundrect_rratio 0.165)
			(net "RXD_IN")
		)
		(pad "2" smd roundrect
			(at -1.6 -0.25)
			(size 0.3 0.8)
			(layers "F.Cu" "F.Mask" "F.Paste")
			(roundrect_rratio 0.165)
		)
		(pad "3" smd roundrect
			(at -1.6 0.25)
			(size 0.3 0.8)
			(layers "F.Cu" "F.Mask" "F.Paste")
			(roundrect_rratio 0.165)
			(net "TXD")
		)
		(pad "4" smd roundrect
			(at -1.6 0.75)
			(size 0.3 0.8)
			(layers "F.Cu" "F.Mask" "F.Paste")
			(roundrect_rratio 0.165)
			(net "GND")
		)
		(pad "5" smd roundrect
			(at 1.6 0.75)
			(size 0.3 0.8)
			(layers "F.Cu" "F.Mask" "F.Paste")
			(roundrect_rratio 0.165)
			(net "TXD_OUT")
		)
		(pad "6" smd roundrect
			(at 1.6 0.25)
			(size 0.3 0.8)
			(layers "F.Cu" "F.Mask" "F.Paste")
			(roundrect_rratio 0.165)
		)
		(pad "7" smd roundrect
			(at 1.6 -0.25)
			(size 0.3 0.8)
			(layers "F.Cu" "F.Mask" "F.Paste")
			(roundrect_rratio 0.165)
			(net "RXD")
		)
		(pad "8" smd roundrect
			(at 1.6 -0.75)
			(size 0.3 0.8)
			(layers "F.Cu" "F.Mask" "F.Paste")
			(roundrect_rratio 0.165)
			(net "VCC")
		)
	)
	(footprint "Vault:TP001V_SMT_100DIA"
		(layer "F.Cu")
		(at 157.8411 118.4631 90)
		(property "Reference" "TP7"
			(at 3.96 0.20607 90)
			(unlocked yes)
			(layer "F.SilkS")
			(effects
				(font
					(size 0.8 0.8)
					(thickness 0.15)
				)
			)
		)
		(property "Value" "SMT_100DIA"
			(at -2.124202 7.0716 0)
			(unlocked yes)
			(layer "F.SilkS")
			(hide yes)
			(effects
				(font
					(size 1.524 1.524)
					(thickness 0.254)
				)
			)
		)
		(sheetname "ZED-F9T")
		(sheetfile "ZED-F9T.kicad_sch")
		(duplicate_pad_numbers_are_jumpers no)
		(pad "1" smd circle
			(at 1.397 0 90)
			(size 1 1)
			(layers "F.Cu" "F.Mask" "F.Paste")
			(net "NetTP7_1")
			(solder_mask_margin 0.05)
			(solder_paste_margin 0)
			(thermal_bridge_angle 90)
		)
	)
	(footprint "Vault:FP-RMCF0402-IPC_C"
		(layer "F.Cu")
		(at 175.8497 101.11983 90)
		(property "Reference" "R4"
			(at 2.38506 -0.04793 90)
			(unlocked yes)
			(layer "F.SilkS")
			(effects
				(font
					(size 0.8 0.8)
					(thickness 0.14986)
				)
			)
		)
		(property "Value" "10k"
			(at -2.352802 1.434525 0)
			(unlocked yes)
			(layer "F.SilkS")
			(hide yes)
			(effects
				(font
					(size 1.524 1.524)
					(thickness 0.254)
				)
			)
		)
		(sheetname "ZED-F9T")
		(sheetfile "ZED-F9T.kicad_sch")
		(duplicate_pad_numbers_are_jumpers no)
		(fp_line
			(start -0.65607 -0.675)
			(end 0.65607 -0.675)
			(stroke
				(width 0.2)
				(type solid)
			)
			(layer "F.SilkS")
		)
		(fp_line
			(start -0.65607 0.675)
			(end 0.65607 0.675)
			(stroke
				(width 0.2)
				(type solid)
			)
			(layer "F.SilkS")
		)
		(fp_line
			(start 0.75606 -0.375)
			(end 0.75606 0.375)
			(stroke
				(width 0.2)
				(type solid)
			)
			(layer "F.CrtYd")
		)
		(fp_line
			(start -0.75607 -0.375)
			(end 0.75606 -0.375)
			(stroke
				(width 0.2)
				(type solid)
			)
			(layer "F.CrtYd")
		)
		(fp_line
			(start -0.75607 -0.375)
			(end -0.75607 0.375)
			(stroke
				(width 0.2)
				(type solid)
			)
			(layer "F.CrtYd")
		)
		(fp_line
			(start -0.75607 0.375)
			(end 0.75606 0.375)
			(stroke
				(width 0.2)
				(type solid)
			)
			(layer "F.CrtYd")
		)
		(fp_line
			(start 0 -0.5)
			(end 0 0.5)
			(stroke
				(width 0.1)
				(type solid)
			)
			(layer "F.Fab")
		)
		(fp_line
			(start 0.75606 -0.375)
			(end 0.75606 0.375)
			(stroke
				(width 0.2)
				(type solid)
			)
			(layer "F.Fab")
		)
		(fp_line
			(start -0.75607 -0.375)
			(end 0.75606 -0.375)
			(stroke
				(width 0.2)
				(type solid)
			)
			(layer "F.Fab")
		)
		(fp_line
			(start -0.75607 -0.375)
			(end -0.75607 0.375)
			(stroke
				(width 0.2)
				(type solid)
			)
			(layer "F.Fab")
		)
		(fp_line
			(start -0.5 0)
			(end 0.5 0)
			(stroke
				(width 0.1)
				(type solid)
			)
			(layer "F.Fab")
		)
		(fp_line
			(start -0.75607 0.375)
			(end 0.75606 0.375)
			(stroke
				(width 0.2)
				(type solid)
			)
			(layer "F.Fab")
		)
		(fp_text user "${REFERENCE}"
			(at -0.00002 0.10711 90)
			(unlocked yes)
			(layer "F.Fab")
			(effects
				(font
					(face "Arial")
					(size 0.63 0.63)
					(thickness 0.1)
				)
				(justify left bottom)
			)
		)
		(pad "1" smd rect
			(at -0.36554 0 90)
			(size 0.58106 0.47247)
			(layers "F.Cu" "F.Mask" "F.Paste")
			(net "GND")
			(solder_mask_margin 0)
			(solder_paste_margin 0)
		)
		(pad "2" smd rect
			(at 0.36553 0 90)
			(size 0.58106 0.47247)
			(layers "F.Cu" "F.Mask" "F.Paste")
			(net "NetDS1_K")
			(solder_mask_margin 0)
			(solder_paste_margin 0)
		)
	)
	(footprint "Vault:FP-PESD0402-MFG"
		(layer "F.Cu")
		(at 125.8371 101.9531 90)
		(property "Reference" "D1"
			(at 2.13073 0.15 0)
			(unlocked yes)
			(layer "F.SilkS")
			(effects
				(font
					(size 0.8 0.8)
					(thickness 0.15)
				)
			)
		)
		(property "Value" "PESD0402-140"
			(at -2.378202 8.010865 0)
			(unlocked yes)
			(layer "F.SilkS")
			(hide yes)
			(effects
				(font
					(size 1.524 1.524)
					(thickness 0.254)
				)
			)
		)
		(sheetname "Antenna_Supervisor")
		(sheetfile "Antenna_Supervisor.kicad_sch")
		(duplicate_pad_numbers_are_jumpers no)
		(fp_line
			(start -0.55 -0.7)
			(end 0.55 -0.7)
			(stroke
				(width 0.2)
				(type solid)
			)
			(layer "F.SilkS")
		)
		(fp_line
			(start -0.56 0.69)
			(end 0.54 0.69)
			(stroke
				(width 0.2)
				(type solid)
			)
			(layer "F.SilkS")
		)
		(fp_line
			(start 1.15 -0.425)
			(end 1.15 0.425)
			(stroke
				(width 0.2)
				(type solid)
			)
			(layer "F.CrtYd")
		)
		(fp_line
			(start -1.15 -0.425)
			(end 1.15 -0.425)
			(stroke
				(width 0.2)
				(type solid)
			)
			(layer "F.CrtYd")
		)
		(fp_line
			(start -1.15 -0.425)
			(end -1.15 0.425)
			(stroke
				(width 0.2)
				(type solid)
			)
			(layer "F.CrtYd")
		)
		(fp_line
			(start -1.15 0.425)
			(end 1.15 0.425)
			(stroke
				(width 0.2)
				(type solid)
			)
			(layer "F.CrtYd")
		)
		(fp_line
			(start 0 -0.5)
			(end 0 0.5)
			(stroke
				(width 0.1)
				(type solid)
			)
			(layer "F.Fab")
		)
		(fp_line
			(start 1.15 -0.425)
			(end 1.15 0.425)
			(stroke
				(width 0.2)
				(type solid)
			)
			(layer "F.Fab")
		)
		(fp_line
			(start -1.15 -0.425)
			(end 1.15 -0.425)
			(stroke
				(width 0.2)
				(type solid)
			)
			(layer "F.Fab")
		)
		(fp_line
			(start -1.15 -0.425)
			(end -1.15 0.425)
			(stroke
				(width 0.2)
				(type solid)
			)
			(layer "F.Fab")
		)
		(fp_line
			(start -0.5 0)
			(end 0.5 0)
			(stroke
				(width 0.1)
				(type solid)
			)
			(layer "F.Fab")
		)
		(fp_line
			(start -1.15 0.425)
			(end 1.15 0.425)
			(stroke
				(width 0.2)
				(type solid)
			)
			(layer "F.Fab")
		)
		(fp_text user "${REFERENCE}"
			(at -0.1524 -1.0105 90)
			(unlocked yes)
			(layer "F.Fab")
			(effects
				(font
					(face "Arial")
					(size 0.63 0.63)
					(thickness 0.1)
				)
				(justify left bottom)
			)
		)
		(pad "1" smd rect
			(at -0.625 0 90)
			(size 0.85 0.65)
			(layers "F.Cu" "F.Mask" "F.Paste")
			(net "GND")
			(solder_mask_margin 0)
			(solder_paste_margin 0)
		)
		(pad "2" smd rect
			(at 0.625 0 90)
			(size 0.85 0.65)
			(layers "F.Cu" "F.Mask" "F.Paste")
			(net "RF_ANT")
			(solder_mask_margin 0)
			(solder_paste_margin 0)
		)
	)
	(footprint "Vault:CAPC1005X055N"
		(layer "F.Cu")
		(at 147.3001 94.8411 90)
		(property "Reference" "C5"
			(at 2.182 0.02827 90)
			(unlocked yes)
			(layer "F.SilkS")
			(effects
				(font
					(size 0.8 0.8)
					(thickness 0.15)
				)
			)
		)
		(property "Value" "Murata_GRM155R61E105KA12D"
			(at -2.584202 17.199825 0)
			(unlocked yes)
			(layer "F.SilkS")
			(hide yes)
			(effects
				(font
					(size 1.524 1.524)
					(thickness 0.254)
				)
			)
		)
		(sheetname "ZED-F9T")
		(sheetfile "ZED-F9T.kicad_sch")
		(duplicate_pad_numbers_are_jumpers no)
		(fp_line
			(start 0.95 -0.5)
			(end 0.95 0.5)
			(stroke
				(width 0.1)
				(type solid)
			)
			(layer "F.CrtYd")
		)
		(fp_line
			(start -0.95 -0.5)
			(end 0.95 -0.5)
			(stroke
				(width 0.1)
				(type solid)
			)
			(layer "F.CrtYd")
		)
		(fp_line
			(start -0.95 -0.5)
			(end -0.95 0.5)
			(stroke
				(width 0.1)
				(type solid)
			)
			(layer "F.CrtYd")
		)
		(fp_line
			(start -0.95 0.5)
			(end 0.95 0.5)
			(stroke
				(width 0.1)
				(type solid)
			)
			(layer "F.CrtYd")
		)
		(fp_line
			(start 0.5 -0.25)
			(end 0.5 0.25)
			(stroke
				(width 0.05)
				(type solid)
			)
			(layer "F.Fab")
		)
		(fp_line
			(start -0.5 -0.25)
			(end 0.5 -0.25)
			(stroke
				(width 0.05)
				(type solid)
			)
			(layer "F.Fab")
		)
		(fp_line
			(start -0.5 -0.25)
			(end -0.5 0.25)
			(stroke
				(width 0.05)
				(type solid)
			)
			(layer "F.Fab")
		)
		(fp_line
			(start -0.5 0.25)
			(end 0.5 0.25)
			(stroke
				(width 0.05)
				(type solid)
			)
			(layer "F.Fab")
		)
		(fp_text_box "${REFERENCE}"
			(start -1.09004 -0.20727)
			(end 1.09004 0.20726)
			(margins 0 0 0 0)
			(layer "F.Fab")
			(effects
				(font
					(face "Arial")
					(size 0.315 0.315)
					(thickness 0.254)
				)
				(justify top)
			)
			(border no)
			(stroke
				(width 0.1)
				(type default)
			)
			(knockout no)
		)
		(pad "1" smd rect
			(at -0.46 0 90)
			(size 0.6 0.62)
			(layers "F.Cu" "F.Mask" "F.Paste")
			(net "NetC5_1")
			(solder_mask_margin 0.05)
			(solder_paste_margin 0)
		)
		(pad "2" smd rect
			(at 0.46 0 90)
			(size 0.6 0.62)
			(layers "F.Cu" "F.Mask" "F.Paste")
			(net "GND")
			(solder_mask_margin 0.05)
			(solder_paste_margin 0)
		)
	)
	(footprint "Vault:FP-GRM033-0_03-IPC_B"
		(layer "F.Cu")
		(at 127.6151 104.3661 180)
		(property "Reference" "C10"
			(at 1.678805 -0.00287 0)
			(unlocked yes)
			(layer "F.SilkS")
			(effects
				(font
					(size 0.8 0.8)
					(thickness 0.15)
				)
			)
		)
		(property "Value" "10nF"
			(at -2.39944 -2.251202 0)
			(unlocked yes)
			(layer "F.SilkS")
			(hide yes)
			(effects
				(font
					(size 1.524 1.524)
					(thickness 0.254)
				)
			)
		)
		(sheetname "Antenna_Supervisor")
		(sheetfile "Antenna_Supervisor.kicad_sch")
		(duplicate_pad_numbers_are_jumpers no)
		(fp_line
			(start 0.53137 0.58137)
			(end -0.53137 0.58137)
			(stroke
				(width 0.2)
				(type solid)
			)
			(layer "F.SilkS")
		)
		(fp_line
			(start 0.53137 -0.58137)
			(end -0.53137 -0.58137)
			(stroke
				(width 0.2)
				(type solid)
			)
			(layer "F.SilkS")
		)
		(fp_line
			(start 0.68137 0.33137)
			(end -0.68137 0.33137)
			(stroke
				(width 0.2)
				(type solid)
			)
			(layer "F.CrtYd")
		)
		(fp_line
			(start 0.68137 -0.33137)
			(end 0.68137 0.33137)
			(stroke
				(width 0.2)
				(type solid)
			)
			(layer "F.CrtYd")
		)
		(fp_line
			(start 0.68137 -0.33137)
			(end -0.68137 -0.33137)
			(stroke
				(width 0.2)
				(type solid)
			)
			(layer "F.CrtYd")
		)
		(fp_line
			(start -0.68137 -0.33137)
			(end -0.68137 0.33137)
			(stroke
				(width 0.2)
				(type solid)
			)
			(layer "F.CrtYd")
		)
		(fp_line
			(start 0.68137 0.33137)
			(end -0.68137 0.33137)
			(stroke
				(width 0.2)
				(type solid)
			)
			(layer "F.Fab")
		)
		(fp_line
			(start 0.68137 -0.33137)
			(end 0.68137 0.33137)
			(stroke
				(width 0.2)
				(type solid)
			)
			(layer "F.Fab")
		)
		(fp_line
			(start 0.68137 -0.33137)
			(end -0.68137 -0.33137)
			(stroke
				(width 0.2)
				(type solid)
			)
			(layer "F.Fab")
		)
		(fp_line
			(start 0.5 0)
			(end -0.5 0)
			(stroke
				(width 0.1)
				(type solid)
			)
			(layer "F.Fab")
		)
		(fp_line
			(start 0 -0.5)
			(end 0 0.5)
			(stroke
				(width 0.1)
				(type solid)
			)
			(layer "F.Fab")
		)
		(fp_line
			(start -0.68137 -0.33137)
			(end -0.68137 0.33137)
			(stroke
				(width 0.2)
				(type solid)
			)
			(layer "F.Fab")
		)
		(fp_text user "${REFERENCE}"
			(at 0.7366 -1.64587 360)
			(unlocked yes)
			(layer "F.Fab")
			(effects
				(font
					(face "Arial")
					(size 0.63 0.63)
					(thickness 0.1)
				)
				(justify left bottom)
			)
		)
		(pad "1" smd rect
			(at -0.30431 0 180)
			(size 0.45411 0.36274)
			(layers "F.Cu" "F.Mask" "F.Paste")
			(net "NetC10_1")
			(solder_mask_margin 0)
			(solder_paste_margin 0)
		)
		(pad "2" smd rect
			(at 0.30431 0 180)
			(size 0.45411 0.36274)
			(layers "F.Cu" "F.Mask" "F.Paste")
			(net "GND")
			(solder_mask_margin 0)
			(solder_paste_margin 0)
		)
	)
	(footprint "Vault:FP-0402-L_1_0_0_05-W_0_5-IPC_B"
		(layer "F.Cu")
		(at 168.808 109.8525)
		(property "Reference" "C6"
			(at 0.1305 1.52687 360)
			(unlocked yes)
			(layer "F.SilkS")
			(effects
				(font
					(size 0.8 0.8)
					(thickness 0.15)
				)
			)
		)
		(property "Value" "100nF"
			(at 2.95799 2.352802 0)
			(unlocked yes)
			(layer "F.SilkS")
			(hide yes)
			(effects
				(font
					(size 1.524 1.524)
					(thickness 0.254)
				)
			)
		)
		(sheetname "ZED-F9T")
		(sheetfile "ZED-F9T.kicad_sch")
		(duplicate_pad_numbers_are_jumpers no)
		(fp_line
			(start -0.73624 -0.68624)
			(end 0.73623 -0.68624)
			(stroke
				(width 0.2)
				(type solid)
			)
			(layer "F.SilkS")
		)
		(fp_line
			(start -0.73624 0.68624)
			(end 0.73623 0.68624)
			(stroke
				(width 0.2)
				(type solid)
			)
			(layer "F.SilkS")
		)
		(fp_line
			(start -0.88624 -0.43624)
			(end 0.88623 -0.43624)
			(stroke
				(width 0.2)
				(type solid)
			)
			(layer "F.CrtYd")
		)
		(fp_line
			(start -0.88624 0.43624)
			(end -0.88624 -0.43624)
			(stroke
				(width 0.2)
				(type solid)
			)
			(layer "F.CrtYd")
		)
		(fp_line
			(start -0.88624 0.43624)
			(end 0.88623 0.43624)
			(stroke
				(width 0.2)
				(type solid)
			)
			(layer "F.CrtYd")
		)
		(fp_line
			(start 0.88623 0.43624)
			(end 0.88623 -0.43624)
			(stroke
				(width 0.2)
				(type solid)
			)
			(layer "F.CrtYd")
		)
		(fp_line
			(start -0.88624 -0.43624)
			(end 0.88623 -0.43624)
			(stroke
				(width 0.2)
				(type solid)
			)
			(layer "F.Fab")
		)
		(fp_line
			(start -0.88624 0.43624)
			(end -0.88624 -0.43624)
			(stroke
				(width 0.2)
				(type solid)
			)
			(layer "F.Fab")
		)
		(fp_line
			(start -0.88624 0.43624)
			(end 0.88623 0.43624)
			(stroke
				(width 0.2)
				(type solid)
			)
			(layer "F.Fab")
		)
		(fp_line
			(start -0.5 0)
			(end 0.5 0)
			(stroke
				(width 0.1)
				(type solid)
			)
			(layer "F.Fab")
		)
		(fp_line
			(start 0 0.5)
			(end 0 -0.5)
			(stroke
				(width 0.1)
				(type solid)
			)
			(layer "F.Fab")
		)
		(fp_line
			(start 0.88623 0.43624)
			(end 0.88623 -0.43624)
			(stroke
				(width 0.2)
				(type solid)
			)
			(layer "F.Fab")
		)
		(fp_text user "${REFERENCE}"
			(at -0.00002 0.09648 360)
			(unlocked yes)
			(layer "F.Fab")
			(effects
				(font
					(face "Arial")
					(size 0.63 0.63)
					(thickness 0.1)
				)
				(justify left bottom)
			)
		)
		(pad "1" smd rect
			(at -0.42856 0)
			(size 0.61535 0.57247)
			(layers "F.Cu" "F.Mask" "F.Paste")
			(net "VCC")
			(solder_mask_margin 0)
			(solder_paste_margin 0)
		)
		(pad "2" smd rect
			(at 0.42856 0)
			(size 0.61535 0.57247)
			(layers "F.Cu" "F.Mask" "F.Paste")
			(net "GND")
			(solder_mask_margin 0)
			(solder_paste_margin 0)
		)
	)
)
